# T6G (Grand Teton) — schematic netlist excerpt (pin names and nets, part order shuffled) for the footprints in the layout excerpt that follows; sources: Cadence DE-HDL packaged netlist, KiCad conversion of 04192023_DAF0TMB3IC0_F0TG_MB_C_brd_V02_OCP.brd

R839  Q_RES  1K 1% CHIP  pkg 0201LF  page 185 : A = P1V8_CPU0_RT_1D ; B = SMB_RT_CPU0_P3_ROM_R_SCL
C285  Q_CAP  1UF 4V 20% X6S  pkg 0201  page 323 : A = P0V9_CPU1_RT0_2A ; B = GND
R255  Q_RES  0 5% CHIP  pkg 0402LF  page 81 : A = RST_CPU0_PERST1_N ; B = RST_CPU0_PERST1_R_N
L9  Q_INDUCTOR  BLM21SN300SN1D/5A IND  pkg SMLF  page 356 : \1\ = P1V8_CPU1_RT_1D ; \2\ = P1V8_CPU1_RT3_1A

(kicad_pcb
	(version 20260206)
	(generator "pcbnew")
	(generator_version "10.0")
	(general
		(thickness 1.6)
		(legacy_teardrops no)
	)
	(paper "A4")
	(title_block
		(title "04192023_DAF0TMB3IC0_F0TG_MB_C_brd_V02_OCP.brd")
		(comment 1 "Grand Teton / footprints 5801-5804 of 8354")
	)
	(layers
		(0 "F.Cu" signal "TOP")
		(4 "In1.Cu" signal "GND")
		(6 "In2.Cu" signal "IN1")
		(8 "In3.Cu" signal "GND1")
		(10 "In4.Cu" signal "IN2")
		(12 "In5.Cu" signal "GND2")
		(14 "In6.Cu" signal "IN3")
		(16 "In7.Cu" signal "GND3")
		(18 "In8.Cu" signal "VCC")
		(20 "In9.Cu" signal "VCC1")
		(22 "In10.Cu" signal "GND4")
		(24 "In11.Cu" signal "IN4")
		(26 "In12.Cu" signal "GND5")
		(28 "In13.Cu" signal "IN5")
		(30 "In14.Cu" signal "GND6")
		(32 "In15.Cu" signal "IN6")
		(34 "In16.Cu" signal "GND7")
		(2 "B.Cu" signal "BOTTOM")
		(9 "F.Adhes" user "F.Adhesive")
		(11 "B.Adhes" user "B.Adhesive")
		(13 "F.Paste" user "Package Geometry/Pastemask Top")
		(15 "B.Paste" user "Package Geometry/Pastemask Bottom")
		(5 "F.SilkS" user "Ref Des/Silkscreen Top")
		(7 "B.SilkS" user "Ref Des/Silkscreen Bottom")
		(1 "F.Mask" user "Board Geometry/Soldermask Top")
		(3 "B.Mask" user "Board Geometry/Soldermask Bottom")
		(17 "Dwgs.User" user "User.Drawings")
		(19 "Cmts.User" user "User.Comments")
		(21 "Eco1.User" user "User.Eco1")
		(23 "Eco2.User" user "User.Eco2")
		(25 "Edge.Cuts" user "Board Geometry/Outline")
		(27 "Margin" user)
		(31 "F.CrtYd" user "Package Geometry/Place Bound Top")
		(29 "B.CrtYd" user "Package Geometry/Place Bound Bottom")
		(35 "F.Fab" user "Ref Des/Assembly Top")
		(33 "B.Fab" user "Ref Des/Assembly Bottom")
	)
	(footprint ""
		(layer "B.Cu")
		(at 137.352278 -384.575558)
		(property "Reference" "L9"
			(at 0 0 0)
			(layer "B.SilkS")
			(hide yes)
			(effects
				(font
					(size 1.27 1.27)
				)
				(justify mirror)
			)
		)
		(property "Value" ""
			(at 0 0 0)
			(layer "B.Fab")
			(effects
				(font
					(size 1.27 1.27)
				)
				(justify mirror)
			)
		)
		(duplicate_pad_numbers_are_jumpers no)
		(fp_line
			(start -1.63576 -0.8128)
			(end -1.63576 0.8128)
			(stroke
				(width 0.1524)
				(type default)
			)
			(layer "B.SilkS")
		)
		(fp_line
			(start -1.63576 0.8128)
			(end 1.63576 0.8128)
			(stroke
				(width 0.1524)
				(type default)
			)
			(layer "B.SilkS")
		)
		(fp_line
			(start 1.63576 -0.8128)
			(end -1.63576 -0.8128)
			(stroke
				(width 0.1524)
				(type default)
			)
			(layer "B.SilkS")
		)
		(fp_line
			(start 1.63576 -0.8128)
			(end 1.63576 0.8128)
			(stroke
				(width 0.1524)
				(type default)
			)
			(layer "B.SilkS")
		)
		(fp_line
			(start -1.560576 -0.738632)
			(end 1.56083 -0.738632)
			(stroke
				(width 0.1)
				(type default)
			)
			(layer "B.Fab")
		)
		(fp_line
			(start -1.560576 0.7366)
			(end -1.560576 -0.738632)
			(stroke
				(width 0.1)
				(type default)
			)
			(layer "B.Fab")
		)
		(fp_line
			(start -1.524 0.7366)
			(end -1.560576 0.7366)
			(stroke
				(width 0.1)
				(type default)
			)
			(layer "B.Fab")
		)
		(fp_line
			(start 1.524 0.7366)
			(end -1.524 0.7366)
			(stroke
				(width 0.1)
				(type default)
			)
			(layer "B.Fab")
		)
		(fp_line
			(start 1.56083 -0.738632)
			(end 1.56083 0.7366)
			(stroke
				(width 0.1)
				(type default)
			)
			(layer "B.Fab")
		)
		(fp_line
			(start 1.56083 0.7366)
			(end 1.524 0.7366)
			(stroke
				(width 0.1)
				(type default)
			)
			(layer "B.Fab")
		)
		(pad "1" smd rect
			(at 0.94996 0)
			(size 1.1176 1.3716)
			(layers "B.Cu" "B.Mask" "B.Paste")
			(net "P1V8_CPU1_RT_1D")
		)
		(pad "2" smd rect
			(at -0.94996 0)
			(size 1.1176 1.3716)
			(layers "B.Cu" "B.Mask" "B.Paste")
			(net "P1V8_CPU1_RT3_1A")
		)
	)
	(footprint ""
		(layer "B.Cu")
		(at 368.54892 -425.775882 90)
		(property "Reference" "R839"
			(at 0 0 90)
			(layer "B.SilkS")
			(hide yes)
			(effects
				(font
					(size 1.27 1.27)
				)
				(justify mirror)
			)
		)
		(property "Value" ""
			(at 0 0 90)
			(layer "B.Fab")
			(effects
				(font
					(size 1.27 1.27)
				)
				(justify mirror)
			)
		)
		(duplicate_pad_numbers_are_jumpers no)
		(fp_line
			(start 0.32512 -0.175006)
			(end -0.32512 -0.175006)
			(stroke
				(width 0.1)
				(type default)
			)
			(layer "B.Fab")
		)
		(fp_line
			(start -0.32512 -0.175006)
			(end -0.32512 0.175006)
			(stroke
				(width 0.1)
				(type default)
			)
			(layer "B.Fab")
		)
		(fp_line
			(start 0.32512 0.175006)
			(end 0.32512 -0.175006)
			(stroke
				(width 0.1)
				(type default)
			)
			(layer "B.Fab")
		)
		(fp_line
			(start -0.32512 0.175006)
			(end 0.32512 0.175006)
			(stroke
				(width 0.1)
				(type default)
			)
			(layer "B.Fab")
		)
		(pad "1" smd rect
			(at 0.2667 0 270)
			(size 0.3048 0.381)
			(layers "B.Cu" "B.Mask" "B.Paste")
			(net "P1V8_CPU0_RT_1D")
		)
		(pad "2" smd rect
			(at -0.2667 0 90)
			(size 0.3048 0.381)
			(layers "B.Cu" "B.Mask" "B.Paste")
			(net "SMB_RT_CPU0_P3_ROM_R_SCL")
		)
	)
	(footprint ""
		(layer "B.Cu")
		(at 64.178688 -386.766562 90)
		(property "Reference" "C285"
			(at 0 0 90)
			(layer "B.SilkS")
			(hide yes)
			(effects
				(font
					(size 1.27 1.27)
				)
				(justify mirror)
			)
		)
		(property "Value" ""
			(at 0 0 90)
			(layer "B.Fab")
			(effects
				(font
					(size 1.27 1.27)
				)
				(justify mirror)
			)
		)
		(duplicate_pad_numbers_are_jumpers no)
		(fp_line
			(start 0.299974 -0.150114)
			(end -0.299974 -0.150114)
			(stroke
				(width 0.1)
				(type default)
			)
			(layer "B.Fab")
		)
		(fp_line
			(start -0.299974 -0.150114)
			(end -0.299974 0.150114)
			(stroke
				(width 0.1)
				(type default)
			)
			(layer "B.Fab")
		)
		(fp_line
			(start 0.299974 0.150114)
			(end 0.299974 -0.150114)
			(stroke
				(width 0.1)
				(type default)
			)
			(layer "B.Fab")
		)
		(fp_line
			(start -0.299974 0.150114)
			(end 0.299974 0.150114)
			(stroke
				(width 0.1)
				(type default)
			)
			(layer "B.Fab")
		)
		(pad "1" smd rect
			(at 0.2667 0 270)
			(size 0.3048 0.381)
			(layers "B.Cu" "B.Mask" "B.Paste")
			(net "P0V9_CPU1_RT0_2A")
		)
		(pad "2" smd rect
			(at -0.2667 0 270)
			(size 0.3048 0.381)
			(layers "B.Cu" "B.Mask" "B.Paste")
			(net "GND")
		)
	)
	(footprint ""
		(layer "B.Cu")
		(at 176.543208 -127.643636 180)
		(property "Reference" "R255"
			(at 0 0 0)
			(layer "B.SilkS")
			(hide yes)
			(effects
				(font
					(size 1.27 1.27)
				)
				(justify mirror)
			)
		)
		(property "Value" ""
			(at 0 0 0)
			(layer "B.Fab")
			(effects
				(font
					(size 1.27 1.27)
				)
				(justify mirror)
			)
		)
		(duplicate_pad_numbers_are_jumpers no)
		(fp_line
			(start 0.7874 0.4064)
			(end 0.7874 -0.4064)
			(stroke
				(width 0.1524)
				(type default)
			)
			(layer "B.SilkS")
		)
		(fp_line
			(start 0.7874 -0.4064)
			(end -0.7874 -0.4064)
			(stroke
				(width 0.1524)
				(type default)
			)
			(layer "B.SilkS")
		)
		(fp_line
			(start -0.7874 0.4064)
			(end 0.7874 0.4064)
			(stroke
				(width 0.1524)
				(type default)
			)
			(layer "B.SilkS")
		)
		(fp_line
			(start -0.7874 -0.4064)
			(end -0.7874 0.4064)
			(stroke
				(width 0.1524)
				(type default)
			)
			(layer "B.SilkS")
		)
		(fp_line
			(start 0.67945 0.3048)
			(end 0.67945 -0.305054)
			(stroke
				(width 0.1)
				(type default)
			)
			(layer "B.Fab")
		)
		(fp_line
			(start 0.67945 -0.305054)
			(end 0.12065 -0.305054)
			(stroke
				(width 0.1)
				(type default)
			)
			(layer "B.Fab")
		)
		(fp_line
			(start 0.12065 0.3048)
			(end 0.67945 0.3048)
			(stroke
				(width 0.1)
				(type default)
			)
			(layer "B.Fab")
		)
		(fp_line
			(start 0.12065 0.2794)
			(end 0.12065 0.3048)
			(stroke
				(width 0.1)
				(type default)
			)
			(layer "B.Fab")
		)
		(fp_line
			(start 0.12065 -0.2794)
			(end -0.12065 -0.2794)
			(stroke
				(width 0.1)
				(type default)
			)
			(layer "B.Fab")
		)
		(fp_line
			(start 0.12065 -0.305054)
			(end 0.12065 -0.2794)
			(stroke
				(width 0.1)
				(type default)
			)
			(layer "B.Fab")
		)
		(fp_line
			(start -0.120396 0.3048)
			(end -0.120396 0.2794)
			(stroke
				(width 0.1)
				(type default)
			)
			(layer "B.Fab")
		)
		(fp_line
			(start -0.120396 0.2794)
			(end 0.12065 0.2794)
			(stroke
				(width 0.1)
				(type default)
			)
			(layer "B.Fab")
		)
		(fp_line
			(start -0.12065 -0.2794)
			(end -0.12065 -0.3048)
			(stroke
				(width 0.1)
				(type default)
			)
			(layer "B.Fab")
		)
		(fp_line
			(start -0.12065 -0.3048)
			(end -0.67945 -0.3048)
			(stroke
				(width 0.1)
				(type default)
			)
			(layer "B.Fab")
		)
		(fp_line
			(start -0.67945 0.3048)
			(end -0.120396 0.3048)
			(stroke
				(width 0.1)
				(type default)
			)
			(layer "B.Fab")
		)
		(fp_line
			(start -0.67945 -0.3048)
			(end -0.67945 0.3048)
			(stroke
				(width 0.1)
				(type default)
			)
			(layer "B.Fab")
		)
		(pad "1" smd circle
			(at 0.40005 0)
			(size 0 0)
			(layers "B.Cu" "B.Mask" "B.Paste")
			(net "RST_CPU0_PERST1_N")
		)
		(pad "2" smd circle
			(at -0.40005 0)
			(size 0 0)
			(layers "B.Cu" "B.Mask" "B.Paste")
			(net "RST_CPU0_PERST1_R_N")
		)
	)
)
